FILE_TYPE = CONNECTIVITY;
{Allegro Design Entry HDL 17.2-2016 S081 (4005846) 1/11/2022}
"PAGE_NUMBER" = 199;
0"NC";
1"GND\g";
2"GND\g";
3"GND\g";
4"GND\g";
5"GND\g";
6"GND\g";
7"GND\g";
8"GND\g";
9"GND\g";
10"PVDD18_S5_P0\g";
11"PVDD11_S3_P1\g";
12"GND\g";
13"GND\g";
14"GND\g";
15"GND\g";
16"GND\g";
17"GND\g";
18"GND\g";
19"GND\g";
20"GND\g";
21"GND\g";
22"VSENSE_VSS_SENSE_C_P1";
23"VSENSE_PVDD11_S3_P1_DP";
24"PVDD11_S3_P1_VCC";
25"PVDD11_S3_P1_PWM1";
26"PVDD11_S3_P1_IMON1";
27"PVDD11_S3_P1_VCCS";
28"PVDD11_S3_P1_RESET_N";
29"NC_PVDD11_S3_P1_PWM6";
30"NC_PVDD11_S3_P1_PWM7";
31"NC_PVDD11_S3_P1_IMON4";
32"NC_PVDD11_S3_P1_IMON7";
33"NC_PVDD11_S3_P1_IMON6";
34"NC_PVDD11_S3_P1_PWM8";
35"NC_PVDD11_S3_P1_IMON8";
36"PVDD11_S3_P1_TEMP1";
37"PVDD11_S3_P1_TEMP0";
38"PVDD11_S3_P1_PMSDA_R";
39"PVDD11_S3_P1_PMSCL_R";
40"PVDD11_S3_P1_PMALERT";
41"SMB_SCM_6_R1_SDA";
42"SMB_SCM_6_R1_SCL";
43"PWRGD_PVDD11_S3_P1";
44"PVDD11_S3_P1_OCP_N_R";
45"NC_PVDD11_S3_P1_PG1";
46"PVDD11_S3_P1_VINSEN";
47"VSENSE_PVDD11_S3_P1_R";
48"NC_PVDD11_S3_P1_IMON3";
49"NC_PVDD11_S3_P1_PWM3";
50"PVDD11_S3_P1_PMALERT_R";
51"PVDD11_S3_P1_RESET_N_R";
52"PVDD11_S3_P1_OCP_N";
53"PVDD11_S3_P1_VDDIO";
54"PVDD11_S3_P1_VMON";
55"PVDD11_S3_P1_ADDR_CFG";
56"NC_PVDD11_S3_P1_PWM4";
57"NC_PVDD11_S3_P1_IMON5";
58"NC_PVDD11_S3_P1_PWM5";
59"PVDD11_S3_P1_EN";
60"GND\g";
61"GND\g";
62"P12V_STBY\g";
63"P3V3_STBY\g";
64"PVDD18_S5_P1\g";
65"GND\g";
66"P3V3_STBY\g";
67"GND\g";
68"P3V3_STBY\g";
69"P5V_STBY\g";
70"PWRGD_PVDD11_S3_P1_R";
71"PVDD11_S3_P1_EN_R";
72"GND\g";
73"NC_PVDD11_S3_P1_SVTO";
74"PVDD11_S3_P1_IMON2";
75"PVDD11_S3_P1_PWM2";
%"UNIVERSAL_GND"
"1","(-2925,5925)","0","pure_quanta_power","I10";
;
HDL_POWER"GND"
CDS_LIB"pure_quanta_power";
"A"1;
%"Q_CAP"
"1","(-5325,475)","0","pure_quanta","I100";
;
LOCATION"PC8"
SEC"1"
PACK_TYPE"0402"
VOLTAGE"25V"
PART_NUMBER"CH4104K1B00"
VALUE"0.1UF"
TOLERANCE"10%"
MATERIAL"X7R"
CDS_LIB"pure_quanta"
SEC_TYPE"0402";
"B"
$PN"2"2;
"A"
$PN"1"46;
%"Q_RES"
"1","(-5975,650)","0","pure_quanta","I101";
;
LOCATION"PR388"
$SEC"1"
CDS_SEC"1"
PACK_TYPE"0402LF"
VALUE"0"
TOLERANCE"5%"
MATERIAL"CHIP"
WATTAGE"1/16W"
PART_NUMBER"CS00002JB38"
CDS_LIB"pure_quanta";
"B"
$PN"2"46;
"A"
$PN"1"62;
%"UNIVERSAL_GND"
"1","(-5325,250)","0","pure_quanta_power","I102";
;
HDL_POWER"GND"
CDS_LIB"pure_quanta_power";
"A"2;
%"Q_RES"
"1","(-7200,825)","0","pure_quanta","I104";
;
LOCATION"PR376"
$SEC"1"
CDS_SEC"1"
PACK_TYPE"0402LF"
PART_NUMBER"TMP_QCS34022FB15"
VALUE"40.2K"
TOLERANCE"1%"
MATERIAL"CHIP"
WATTAGE"1/16W"
CDS_LIB"pure_quanta";
"B"
$PN"2"54;
"A"
$PN"1"69;
%"Q_RES"
"2","(-6450,650)","0","pure_quanta","I105";
;
LOCATION"PR6"
SEC"1"
PACK_TYPE"0402LF"
VALUE"10K"
TOLERANCE"1%"
MATERIAL"CHIP"
WATTAGE"1/16W"
PART_NUMBER"TMP_QCS31002FB26"
CDS_LIB"pure_quanta"
SEC_TYPE"0402LF";
"A"
$PN"1"54;
"B"
$PN"2"3;
%"UNIVERSAL_GND"
"1","(-6450,375)","0","pure_quanta_power","I107";
;
HDL_POWER"GND"
CDS_LIB"pure_quanta_power";
"A"3;
%"UNIVERSAL_GND"
"1","(-6875,400)","0","pure_quanta_power","I108";
;
HDL_POWER"GND"
CDS_LIB"pure_quanta_power";
"A"4;
%"VCC_CORE"
"1","(-7550,925)","0","pure_quanta_power","I109";
;
HDL_POWER"P5V_STBY"
CDS_LIB"pure_quanta_power";
"A"69;
%"Q_CAP"
"1","(-6875,650)","0","pure_quanta","I118";
;
LOCATION"PC638"
$SEC"1"
CDS_SEC"1"
PACK_TYPE"0402"
VOLTAGE"25V"
PART_NUMBER"CH4104K1B00"
VALUE"0.1UF"
TOLERANCE"10%"
MATERIAL"X7R"
CDS_LIB"pure_quanta";
"B"
$PN"2"4;
"A"
$PN"1"54;
%"UNIVERSAL_GND"
"1","(-2925,5425)","0","pure_quanta_power","I12";
;
HDL_POWER"GND"
CDS_LIB"pure_quanta_power";
"A"5;
%"Q_CAP"
"1","(-2925,5650)","0","pure_quanta","I13";
;
LOCATION"PC644"
$SEC"1"
CDS_SEC"1"
PACK_TYPE"C0402"
VOLTAGE"6.3V"
PART_NUMBER"CH6101MEB01"
VALUE"10UF"
TOLERANCE"20%"
MATERIAL"X6S"
CDS_LIB"pure_quanta";
"B"
$PN"2"5;
"A"
$PN"1"27;
%"VCC_CORE"
"1","(-2125,6375)","0","pure_quanta_power","I14";
;
HDL_POWER"P3V3_STBY"
CDS_LIB"pure_quanta_power";
"A"68;
%"UNIVERSAL_GND"
"1","(-5300,2550)","2","pure_quanta_power","I146";
;
HDL_POWER"GND"
CDS_LIB"pure_quanta_power";
"A"67;
%"Q_RES"
"1","(-2500,6275)","0","pure_quanta","I148";
;
LOCATION"PR393"
$SEC"1"
CDS_SEC"1"
PACK_TYPE"0402LF"
PART_NUMBER"CS-1002FB23"
VALUE"1"
TOLERANCE"1%"
MATERIAL"CHIP"
WATTAGE"1/16W"
CDS_LIB"pure_quanta";
"B"
$PN"2"68;
"A"
$PN"1"24;
%"VCC_CORE"
"1","(-6525,6500)","0","pure_quanta_power","I150";
;
HDL_POWER"P3V3_STBY"
CDS_LIB"pure_quanta_power";
"A"66;
%"Q_RES"
"1","(-6125,6375)","0","pure_quanta","I151";
;
LOCATION"PR380"
$SEC"1"
CDS_SEC"1"
TOLERANCE"1%"
PACK_TYPE"0402LF"
PART_NUMBER"TMP_QCS21002FB24"
VALUE"1K"
MATERIAL"CHIP"
WATTAGE"1/16W"
CDS_LIB"pure_quanta";
"B"
$PN"2"70;
"A"
$PN"1"66;
%"Q_RES"
"1","(-5900,6100)","0","pure_quanta","I152";
;
LOCATION"PR385"
$SEC"1"
CDS_SEC"1"
PART_NUMBER"CS00002JB38"
VALUE"0"
TOLERANCE"5%"
MATERIAL"CHIP"
WATTAGE"1/16W"
PACK_TYPE"0402LF"
CDS_LIB"pure_quanta";
"B"
$PN"2"70;
"A"
$PN"1"43;
%"Q_CAP"
"2","(-5250,6375)","0","pure_quanta","I153";
;
LOCATION"PC641"
$SEC"1"
CDS_SEC"1"
PACK_TYPE"0402"
VOLTAGE"50V"
PART_NUMBER"TMP_QCH21006JB10"
VALUE"1000PF"
TOLERANCE"5%"
MATERIAL"EMPTY"
CDS_LIB"pure_quanta";
"A"
$PN"1"70;
"B"
$PN"2"65;
%"UNIVERSAL_GND"
"1","(-5000,6300)","0","pure_quanta_power","I154";
;
HDL_POWER"GND"
CDS_LIB"pure_quanta_power";
"A"65;
%"UNIVERSAL_GND"
"1","(-3300,5425)","0","pure_quanta_power","I159";
;
HDL_POWER"GND"
CDS_LIB"pure_quanta_power";
"A"6;
%"Q_CAP"
"1","(-3300,5650)","0","pure_quanta","I160";
;
LOCATION"PC96"
$SEC"1"
CDS_SEC"1"
PACK_TYPE"0402"
VOLTAGE"25V"
VALUE"0.1UF"
TOLERANCE"10%"
MATERIAL"X7R"
PART_NUMBER"CH4104K1B00"
CDS_LIB"pure_quanta";
"B"
$PN"2"6;
"A"
$PN"1"27;
%"UNIVERSAL_GND"
"1","(-3300,5875)","0","pure_quanta_power","I161";
;
HDL_POWER"GND"
CDS_LIB"pure_quanta_power";
"A"7;
%"Q_CAP"
"1","(-3300,6125)","0","pure_quanta","I162";
;
LOCATION"PC95"
$SEC"1"
CDS_SEC"1"
PACK_TYPE"0402"
VOLTAGE"25V"
PART_NUMBER"CH4104K1B00"
VALUE"0.1UF"
TOLERANCE"10%"
MATERIAL"X7R"
CDS_LIB"pure_quanta";
"B"
$PN"2"7;
"A"
$PN"1"24;
%"UNIVERSAL_GND"
"1","(-2600,1125)","0","pure_quanta_power","I164";
;
HDL_POWER"GND"
CDS_LIB"pure_quanta_power";
"A"8;
%"UNIVERSAL_GND"
"1","(-2050,1175)","0","pure_quanta_power","I166";
;
HDL_POWER"GND"
CDS_LIB"pure_quanta_power";
"A"9;
%"Q_RES"
"2","(-2050,1400)","0","pure_quanta","I167";
;
LOCATION"PR390"
$SEC"1"
CDS_SEC"1"
PACK_TYPE"0402LF"
PART_NUMBER"CS00002JB38"
VALUE"0"
TOLERANCE"5%"
MATERIAL"EMPTY"
WATTAGE"1/16W"
CDS_LIB"pure_quanta";
"A"
$PN"1"51;
"B"
$PN"2"9;
%"Q_RES"
"1","(-1575,1600)","0","pure_quanta","I177";
;
LOCATION"PR392"
$SEC"1"
CDS_SEC"1"
PACK_TYPE"0402LF"
PART_NUMBER"CS00002JB38"
VALUE"0"
TOLERANCE"5%"
MATERIAL"EMPTY"
WATTAGE"1/16W"
CDS_LIB"pure_quanta";
"B"
$PN"2"28;
"A"
$PN"1"51;
%"Q_RES"
"1","(-1625,1825)","0","pure_quanta","I178";
;
LOCATION"PR391"
$SEC"1"
CDS_SEC"1"
PACK_TYPE"0402LF"
PART_NUMBER"TMP_QCS21002FB24"
VALUE"1K"
TOLERANCE"1%"
MATERIAL"EMPTY"
WATTAGE"1/16W"
CDS_LIB"pure_quanta";
"B"
$PN"2"64;
"A"
$PN"1"51;
%"VCC_CORE"
"1","(-1275,1975)","0","pure_quanta_power","I179";
;
HDL_POWER"PVDD18_S5_P1"
CDS_LIB"pure_quanta_power";
"A"64;
%"Q_RES"
"1","(-3050,1200)","0","pure_quanta","I182";
;
LOCATION"PR415"
$SEC"1"
CDS_SEC"1"
PACK_TYPE"0402LF"
PART_NUMBER"CS00002JB38"
VALUE"0"
TOLERANCE"5%"
MATERIAL"CHIP"
WATTAGE"1/16W"
CDS_LIB"pure_quanta";
"B"
$PN"2"8;
"A"
$PN"1"36;
%"UNIVERSAL_GND"
"1","(-5975,5100)","0","pure_quanta_power","I232";
;
HDL_POWER"GND"
CDS_LIB"pure_quanta_power";
"A"72;
%"VCC_CORE"
"1","(-6525,1825)","0","pure_quanta_power","I237";
;
HDL_POWER"P3V3_STBY"
CDS_LIB"pure_quanta_power";
"A"63;
%"Q_RES"
"1","(-6100,1700)","0","pure_quanta","I238";
;
LOCATION"PR146"
$SEC"1"
CDS_SEC"1"
PART_NUMBER"CS00002JB38"
VALUE"0"
TOLERANCE"5%"
MATERIAL"EMPTY"
WATTAGE"1/16W"
PACK_TYPE"0402LF"
CDS_LIB"pure_quanta";
"B"
$PN"2"53;
"A"
$PN"1"63;
%"Q_RES"
"1","(-6175,2100)","0","pure_quanta","I240";
;
LOCATION"PR10"
$SEC"1"
CDS_SEC"1"
PACK_TYPE"0402LF"
PART_NUMBER"CS00002JB38"
VALUE"0"
MATERIAL"EMPTY"
TOLERANCE"5%"
WATTAGE"1/16W"
CDS_LIB"pure_quanta";
"B"
$PN"2"44;
"A"
$PN"1"52;
%"Q_RES"
"2","(-5900,2325)","0","pure_quanta","I241";
;
LOCATION"PR11"
$SEC"1"
CDS_SEC"1"
PACK_TYPE"0402LF"
PART_NUMBER"TMP_QCS21002FB24"
VALUE"1K"
TOLERANCE"1%"
MATERIAL"EMPTY"
WATTAGE"1/16W"
CDS_LIB"pure_quanta";
"A"
$PN"1"10;
"B"
$PN"2"44;
%"VCC_CORE"
"1","(-5900,2525)","0","pure_quanta_power","I242";
;
HDL_POWER"PVDD18_S5_P0"
CDS_LIB"pure_quanta_power";
"A"10;
%"Q_RES"
"2","(-6675,4225)","0","pure_quanta","I243";
;
LOCATION"PR229"
$SEC"1"
CDS_SEC"1"
PACK_TYPE"0402LF"
PART_NUMBER"CS04992FB31"
MATERIAL"CHIP"
WATTAGE"1/16W"
VALUE"49.9"
TOLERANCE"1%"
CDS_LIB"pure_quanta";
"A"
$PN"1"11;
"B"
$PN"2"23;
%"VCC_CORE"
"1","(-6675,4425)","0","pure_quanta_power","I244";
;
HDL_POWER"PVDD11_S3_P1"
CDS_LIB"pure_quanta_power";
"A"11;
%"Q_RES"
"2","(-6675,3650)","0","pure_quanta","I245";
;
LOCATION"PR288"
$SEC"1"
CDS_SEC"1"
PACK_TYPE"0402LF"
PART_NUMBER"CS04992FB31"
MATERIAL"CHIP"
WATTAGE"1/16W"
VALUE"49.9"
TOLERANCE"1%"
CDS_LIB"pure_quanta";
"A"
$PN"1"22;
"B"
$PN"2"12;
%"UNIVERSAL_GND"
"1","(-6675,3475)","0","pure_quanta_power","I246";
;
HDL_POWER"GND"
CDS_LIB"pure_quanta_power";
"A"12;
%"Q_RES"
"1","(-5825,1400)","0","pure_quanta","I247";
;
LOCATION"PR464"
$SEC"1"
CDS_SEC"1"
PACK_TYPE"0402LF"
TOLERANCE"1%  "
MATERIAL"CHIP"
WATTAGE"1/16W"
VALUE"13.7K    "
PART_NUMBER"CS31372FB11"
CDS_LIB"pure_quanta";
"B"
$PN"2"55;
"A"
$PN"1"13;
%"UNIVERSAL_GND"
"1","(-6100,1125)","0","pure_quanta_power","I248";
;
HDL_POWER"GND"
CDS_LIB"pure_quanta_power";
"A"13;
%"UNIVERSAL_GND"
"1","(-2600,4025)","0","pure_quanta_power","I269";
;
HDL_POWER"GND"
CDS_LIB"pure_quanta_power";
"A"14;
%"UNIVERSAL_GND"
"1","(-2600,3575)","0","pure_quanta_power","I270";
;
HDL_POWER"GND"
CDS_LIB"pure_quanta_power";
"A"15;
%"Q_RES"
"1","(-3050,4100)","0","pure_quanta","I271";
;
LOCATION"PR406"
$SEC"1"
CDS_SEC"1"
PACK_TYPE"0402LF"
PART_NUMBER"CS00002JB38"
VALUE"0"
TOLERANCE"5%"
WATTAGE"1/16W"
MATERIAL"CHIP"
CDS_LIB"pure_quanta";
"B"
$PN"2"14;
"A"
$PN"1"48;
%"Q_RES"
"1","(-3050,3650)","0","pure_quanta","I272";
;
LOCATION"PR407"
$SEC"1"
CDS_SEC"1"
PACK_TYPE"0402LF"
PART_NUMBER"CS00002JB38"
VALUE"0"
TOLERANCE"5%"
MATERIAL"CHIP"
WATTAGE"1/16W"
CDS_LIB"pure_quanta";
"B"
$PN"2"15;
"A"
$PN"1"31;
%"Q_RES"
"1","(-3050,3200)","0","pure_quanta","I273";
;
LOCATION"PR13"
$SEC"1"
CDS_SEC"1"
PACK_TYPE"0402LF"
PART_NUMBER"CS00002JB38"
VALUE"0"
TOLERANCE"5%"
WATTAGE"1/16W"
MATERIAL"CHIP"
CDS_LIB"pure_quanta";
"B"
$PN"2"16;
"A"
$PN"1"57;
%"UNIVERSAL_GND"
"1","(-2600,3125)","0","pure_quanta_power","I274";
;
HDL_POWER"GND"
CDS_LIB"pure_quanta_power";
"A"16;
%"UNIVERSAL_GND"
"1","(-2600,2675)","0","pure_quanta_power","I275";
;
HDL_POWER"GND"
CDS_LIB"pure_quanta_power";
"A"17;
%"UNIVERSAL_GND"
"1","(-2600,2225)","0","pure_quanta_power","I276";
;
HDL_POWER"GND"
CDS_LIB"pure_quanta_power";
"A"18;
%"UNIVERSAL_GND"
"1","(-2600,1775)","0","pure_quanta_power","I277";
;
HDL_POWER"GND"
CDS_LIB"pure_quanta_power";
"A"19;
%"Q_RES"
"1","(-3050,2750)","0","pure_quanta","I278";
;
LOCATION"PR14"
$SEC"1"
CDS_SEC"1"
PACK_TYPE"0402LF"
PART_NUMBER"CS00002JB38"
VALUE"0"
TOLERANCE"5%"
MATERIAL"CHIP"
WATTAGE"1/16W"
CDS_LIB"pure_quanta";
"B"
$PN"2"17;
"A"
$PN"1"33;
%"Q_RES"
"1","(-3050,2300)","0","pure_quanta","I279";
;
LOCATION"PR408"
$SEC"1"
CDS_SEC"1"
PACK_TYPE"0402LF"
PART_NUMBER"CS00002JB38"
VALUE"0"
TOLERANCE"5%"
MATERIAL"CHIP"
WATTAGE"1/16W"
CDS_LIB"pure_quanta";
"B"
$PN"2"18;
"A"
$PN"1"32;
%"Q_RES"
"1","(-3050,1850)","0","pure_quanta","I280";
;
LOCATION"PR409"
$SEC"1"
CDS_SEC"1"
PACK_TYPE"0402LF"
PART_NUMBER"CS00002JB38"
VALUE"0"
TOLERANCE"5%"
MATERIAL"CHIP"
WATTAGE"1/16W"
CDS_LIB"pure_quanta";
"B"
$PN"2"19;
"A"
$PN"1"35;
%"VCC_CORE"
"1","(-6200,725)","0","pure_quanta_power","I285";
;
HDL_POWER"P12V_STBY"
CDS_LIB"pure_quanta_power";
"A"62;
%"UNIVERSAL_GND"
"1","(-5650,250)","0","pure_quanta_power","I286";
;
HDL_POWER"GND"
CDS_LIB"pure_quanta_power";
"A"20;
%"Q_RES"
"2","(-5650,450)","0","pure_quanta","I287";
;
LOCATION"PR604"
$SEC"1"
CDS_SEC"1"
PACK_TYPE"0402LF"
PART_NUMBER"CS24992FB07"
VALUE"4.99K"
TOLERANCE"1%"
MATERIAL"EMPTY"
WATTAGE"1/16W"
CDS_LIB"pure_quanta";
"A"
$PN"1"46;
"B"
$PN"2"20;
%"Q_CAP"
"1","(-3375,700)","0","pure_quanta","I36";
;
LOCATION"PC643"
$SEC"1"
CDS_SEC"1"
PACK_TYPE"0402"
VOLTAGE"50V"
PART_NUMBER"TMP_QCH14706KB18"
VALUE"470PF"
TOLERANCE"10%"
MATERIAL"X7R"
CDS_LIB"pure_quanta";
"B"
$PN"2"21;
"A"
$PN"1"37;
%"UNIVERSAL_GND"
"1","(-3375,425)","0","pure_quanta_power","I37";
;
HDL_POWER"GND"
CDS_LIB"pure_quanta_power";
"A"21;
%"Q_RES"
"1","(-5900,5950)","0","pure_quanta","I47";
;
LOCATION"PR386"
$SEC"1"
CDS_SEC"1"
PACK_TYPE"0402LF"
PART_NUMBER"CS00002JB38"
TOLERANCE"5%"
MATERIAL"CHIP"
WATTAGE"1/16W"
VALUE"0"
CDS_LIB"pure_quanta";
"B"
$PN"2"71;
"A"
$PN"1"59;
%"Q_CAP"
"2","(-5225,5825)","0","pure_quanta","I49";
;
LOCATION"PC642"
$SEC"1"
CDS_SEC"1"
PART_NUMBER"TMP_QCH21006JB10"
VALUE"1000PF"
TOLERANCE"5%"
MATERIAL"X7R"
PACK_TYPE"0402"
VOLTAGE"50V"
CDS_LIB"pure_quanta";
"A"
$PN"1"71;
"B"
$PN"2"60;
%"UNIVERSAL_GND"
"1","(-5000,5750)","0","pure_quanta_power","I50";
;
HDL_POWER"GND"
CDS_LIB"pure_quanta_power";
"A"60;
%"Q_RES"
"1","(-5975,4950)","0","pure_quanta","I66";
;
LOCATION"PR381"
$SEC"1"
CDS_SEC"1"
PACK_TYPE"0402LF"
PART_NUMBER"CS00002JB38"
VALUE"0"
TOLERANCE"5%"
MATERIAL"CHIP"
WATTAGE"1/16W"
CDS_LIB"pure_quanta";
"B"
$PN"2"39;
"A"
$PN"1"42;
%"Q_RES"
"1","(-5975,4800)","0","pure_quanta","I67";
;
LOCATION"PR382"
$SEC"1"
CDS_SEC"1"
PACK_TYPE"0402LF"
PART_NUMBER"CS00002JB38"
VALUE"0"
TOLERANCE"5%"
MATERIAL"CHIP"
WATTAGE"1/16W"
CDS_LIB"pure_quanta";
"B"
$PN"2"38;
"A"
$PN"1"41;
%"Q_RES"
"1","(-5975,4650)","0","pure_quanta","I68";
;
LOCATION"PR383"
$SEC"1"
CDS_SEC"1"
PACK_TYPE"0402LF"
PART_NUMBER"CS00002JB38"
VALUE"0"
TOLERANCE"5%"
MATERIAL"CHIP"
WATTAGE"1/16W"
CDS_LIB"pure_quanta";
"B"
$PN"2"50;
"A"
$PN"1"40;
%"RAA229621GNPHA0"
"1","(-4325,3350)","0","pure_quanta","I7";
;
LOCATION"PU54"
$SEC"1"
CDS_SEC"1"
MATERIAL"IC"
PART_NUMBER"AR0T6GPV006"
PART_TYPE"SMLF"
VALUE"RAA229621GNP#HA0"
NEEDS_NO_SIZE"TRUE"
CDS_LIB"pure_quanta"
CDS_LMAN_SYM_OUTLINE"-550,2850,500,-2850";
"CS0"
$PN"30"35;
"PWM0"
$PN"1"34;
"TEMP1"
$PN"35"36;
"EN1||ADDR_CFG"
$PN"34"55;
"TH_GND"
$PN"TH"61;
"OCP_L \B"
$PN"33"44;
"CS2"
$PN"28"33;
"PWM2"
$PN"3"29;
"CS3"
$PN"27"57;
"PWM3"
$PN"4"58;
"PWM7"
$PN"8"25;
"CS1"
$PN"29"32;
"RGND1"
$PN"31"67;
"VSEN1"
$PN"32"67;
"VDDIO"
$PN"15"53;
"TEMP0"
$PN"36"37;
"VINSEN"
$PN"38"46;
"VMON||IINSEN"
$PN"37"54;
"VCCS"
$PN"40"27;
"PWM6"
$PN"7"75;
"PG0"
$PN"12"70;
"PWM1"
$PN"2"30;
"VSEN0"
$PN"21"47;
"PWM5"
$PN"6"49;
"PWM4"
$PN"5"56;
"PMSDA"
$PN"9"38;
"RGND0"
$PN"22"22;
"EN0"
$PN"13"71;
"NPMALERT \B"
$PN"11"50;
"SVD"
$PN"17"72;
"PG1"
$PN"16"45;
"CS4"
$PN"26"31;
"CS5"
$PN"25"48;
"RESET_L \B"
$PN"14"51;
"SVTO"
$PN"19"73;
"CS6"
$PN"24"74;
"SVC"
$PN"18"72;
"PMSCL"
$PN"10"39;
"SVTI"
$PN"20"72;
"VCC"
$PN"39"24;
"CS7"
$PN"23"26;
%"Q_CAP"
"1","(-5675,3925)","0","pure_quanta","I76";
;
LOCATION"PC639"
$SEC"1"
CDS_SEC"1"
PACK_TYPE"0402"
VOLTAGE"50V"
PART_NUMBER"TMP_QCH2336K1B12"
VALUE"3300PF"
TOLERANCE"10%"
MATERIAL"X7R"
CDS_LIB"pure_quanta";
"B"
$PN"2"22;
"A"
$PN"1"47;
%"Q_RES"
"1","(-5975,4050)","0","pure_quanta","I77";
;
LOCATION"PR384"
$SEC"1"
CDS_SEC"1"
PACK_TYPE"0402LF"
PART_NUMBER"TMP_QCS01002FB21"
VALUE"10"
TOLERANCE"1%"
MATERIAL"CHIP"
WATTAGE"1/16W"
CDS_LIB"pure_quanta";
"B"
$PN"2"47;
"A"
$PN"1"23;
%"Q_CAP"
"1","(-2925,6125)","0","pure_quanta","I8";
;
LOCATION"PC645"
$SEC"1"
CDS_SEC"1"
PACK_TYPE"C0402"
VOLTAGE"16V"
PART_NUMBER"CH5103KEB01"
VALUE"1UF"
TOLERANCE"10%"
MATERIAL"X6S"
CDS_LIB"pure_quanta";
"B"
$PN"2"1;
"A"
$PN"1"24;
%"UNIVERSAL_GND"
"1","(-5100,450)","0","pure_quanta_power","I99";
;
HDL_POWER"GND"
CDS_LIB"pure_quanta_power";
"A"61;
END.
